FILE_TYPE = MACRO_DRAWING;
SET COLOR_WIRE YELLOW;
SET COLOR_PROP MONO;
SET COLOR_DOT WHITE;
SET COLOR_ARC YELLOW;
SET COLOR_BODY GREEN;
SET COLOR_NOTE MONO;
SET PROP_DISPLAY VALUE;
SET PAGE_NUMBER P252;
FORCEADD INTEL_CORP_BPAGE..1
(-1200 1500);
FORCEPROP 1 LAST CDS_CON_LAST_MODIFIED Fri Jun 16 17:49:35 2017
J 0
(-2625 1825);
PAINT ORANGE (-2625 1825);
DISPLAY INVISIBLE (-2625 1825);
FORCEPROP 1 LAST CUSTOM_TXT_CDS <CURRENT_DESIGN_SHEET> OF <TOTAL_DESIGN_SHEETS>
J 0
(-1700 1525);
PAINT ORANGE (-1700 1525);
FORCEPROP 2 LAST CUSTOM_TXT_CDS <XR_PAGE_TITLE>
J 0
(-9090 6750);
DISPLAY 0.638298 (-9090 6750);
PAINT PINK (-9090 6750);
DISPLAY INVISIBLE (-9090 6750);
FORCEPROP 2 LAST CUSTOM_TXT_CDS <CON_LAST_MODIFIED>
J 0
(-5200 1600);
PAINT ORANGE (-5200 1600);
FORCEPROP 1 LAST SCH_TITLE SMBUS BLOCK DIAGRAM - 2 OF 2
J 0
(-9150 1550);
DISPLAY 2.468085 (-9150 1550);
PAINT ORANGE (-9150 1550);
FORCEPROP 1 LAST COMMENT_BODY TRUE
J 0
(-1188 1512);
DISPLAY 0.468085 (-1188 1512);
PAINT GREEN (-1188 1512);
DISPLAY INVISIBLE (-1188 1512);
FORCEPROP 2 LAST PAGE_BORDER TRUE
J 0
(-9090 6750);
DISPLAY 0.638298 (-9090 6750);
PAINT PINK (-9090 6750);
DISPLAY INVISIBLE (-9090 6750);
FORCEPROP 2 LAST CDS_LIB mstr_symbols
J 0
(-1200 1500);
PAINT MONO (-1200 1500);
DISPLAY INVISIBLE (-1200 1500);
FORCEPROP 2 LAST CDS_XR_PAGE_TITLE CR-260 : @BASEBOARD_FAB2_LIB.BASEBOARD_FAB2(SCH_1):PAGE260
J 0
(-9090 6750);
DISPLAY 0.638298 (-9090 6750);
PAINT PINK (-9090 6750);
DISPLAY INVISIBLE (-9090 6750);
FORCENOTE
$CDS_IMAGE|SMBUS_Topology_NEW_3_20160902.jpg|5000|5000
(-5175 4200) 0;
DISPLAY LEFT (-5175 4200);
QUIT
